FILE_TYPE=LIBRARY_PARTS;
primitive 'SCONN56_123276793';
  pin
    'P12V_B1':
      PIN_NUMBER='(B1)';
      PINUSE='POWER';
      NO_LOAD_CHECK='Both';
      NO_IO_CHECK='Both';
      NO_ASSERT_CHECK='TRUE';
      NO_DIR_CHECK='TRUE';
      ALLOW_CONNECT='TRUE';
    'P12V_B2':
      PIN_NUMBER='(B2)';
      PINUSE='POWER';
      NO_LOAD_CHECK='Both';
      NO_IO_CHECK='Both';
      NO_ASSERT_CHECK='TRUE';
      NO_DIR_CHECK='TRUE';
      ALLOW_CONNECT='TRUE';
    'P12V_B3':
      PIN_NUMBER='(B3)';
      PINUSE='POWER';
      NO_LOAD_CHECK='Both';
      NO_IO_CHECK='Both';
      NO_ASSERT_CHECK='TRUE';
      NO_DIR_CHECK='TRUE';
      ALLOW_CONNECT='TRUE';
    'P12V_B4':
      PIN_NUMBER='(B4)';
      PINUSE='POWER';
      NO_LOAD_CHECK='Both';
      NO_IO_CHECK='Both';
      NO_ASSERT_CHECK='TRUE';
      NO_DIR_CHECK='TRUE';
      ALLOW_CONNECT='TRUE';
    'P12V_B5':
      PIN_NUMBER='(B5)';
      PINUSE='POWER';
      NO_LOAD_CHECK='Both';
      NO_IO_CHECK='Both';
      NO_ASSERT_CHECK='TRUE';
      NO_DIR_CHECK='TRUE';
      ALLOW_CONNECT='TRUE';
    'P12V_B6':
      PIN_NUMBER='(B6)';
      PINUSE='POWER';
      NO_LOAD_CHECK='Both';
      NO_IO_CHECK='Both';
      NO_ASSERT_CHECK='TRUE';
      NO_DIR_CHECK='TRUE';
      ALLOW_CONNECT='TRUE';
    'GND_A1':
      PIN_NUMBER='(A1)';
      PINUSE='POWER';
      NO_LOAD_CHECK='Both';
      NO_IO_CHECK='Both';
      NO_ASSERT_CHECK='TRUE';
      NO_DIR_CHECK='TRUE';
      ALLOW_CONNECT='TRUE';
    'GND_A2':
      PIN_NUMBER='(A2)';
      PINUSE='POWER';
      NO_LOAD_CHECK='Both';
      NO_IO_CHECK='Both';
      NO_ASSERT_CHECK='TRUE';
      NO_DIR_CHECK='TRUE';
      ALLOW_CONNECT='TRUE';
    'GND_A3':
      PIN_NUMBER='(A3)';
      PINUSE='POWER';
      NO_LOAD_CHECK='Both';
      NO_IO_CHECK='Both';
      NO_ASSERT_CHECK='TRUE';
      NO_DIR_CHECK='TRUE';
      ALLOW_CONNECT='TRUE';
    'GND_A4':
      PIN_NUMBER='(A4)';
      PINUSE='POWER';
      NO_LOAD_CHECK='Both';
      NO_IO_CHECK='Both';
      NO_ASSERT_CHECK='TRUE';
      NO_DIR_CHECK='TRUE';
      ALLOW_CONNECT='TRUE';
    'GND_A5':
      PIN_NUMBER='(A5)';
      PINUSE='POWER';
      NO_LOAD_CHECK='Both';
      NO_IO_CHECK='Both';
      NO_ASSERT_CHECK='TRUE';
      NO_DIR_CHECK='TRUE';
      ALLOW_CONNECT='TRUE';
    'GND_A6':
      PIN_NUMBER='(A6)';
      PINUSE='POWER';
      NO_LOAD_CHECK='Both';
      NO_IO_CHECK='Both';
      NO_ASSERT_CHECK='TRUE';
      NO_DIR_CHECK='TRUE';
      ALLOW_CONNECT='TRUE';
    'MFG':
      PIN_NUMBER='(B7)';
      BIDIRECTIONAL='TRUE';
      INPUT_LOAD='(-0.01,0.01)';
      OUTPUT_LOAD='(1.0,-1.0)';
    'RFU':
      PIN_NUMBER='(B8)';
      BIDIRECTIONAL='TRUE';
      INPUT_LOAD='(-0.01,0.01)';
      OUTPUT_LOAD='(1.0,-1.0)';
    'DUALPORTEN#':
      PIN_NUMBER='(B9)';
      BIDIRECTIONAL='TRUE';
      INPUT_LOAD='(-0.01,0.01)';
      OUTPUT_LOAD='(1.0,-1.0)';
    'P3V3_AUX':
      PIN_NUMBER='(B11)';
      PINUSE='POWER';
      NO_LOAD_CHECK='Both';
      NO_IO_CHECK='Both';
      NO_ASSERT_CHECK='TRUE';
      NO_DIR_CHECK='TRUE';
      ALLOW_CONNECT='TRUE';
    'PWRDIS':
      PIN_NUMBER='(B12)';
      BIDIRECTIONAL='TRUE';
      INPUT_LOAD='(-0.01,0.01)';
      OUTPUT_LOAD='(1.0,-1.0)';
    'GND_B13':
      PIN_NUMBER='(B13)';
      PINUSE='POWER';
      NO_LOAD_CHECK='Both';
      NO_IO_CHECK='Both';
      NO_ASSERT_CHECK='TRUE';
      NO_DIR_CHECK='TRUE';
      ALLOW_CONNECT='TRUE';
    'GND_B16':
      PIN_NUMBER='(B16)';
      PINUSE='POWER';
      NO_LOAD_CHECK='Both';
      NO_IO_CHECK='Both';
      NO_ASSERT_CHECK='TRUE';
      NO_DIR_CHECK='TRUE';
      ALLOW_CONNECT='TRUE';
    'GND_B19':
      PIN_NUMBER='(B19)';
      PINUSE='POWER';
      NO_LOAD_CHECK='Both';
      NO_IO_CHECK='Both';
      NO_ASSERT_CHECK='TRUE';
      NO_DIR_CHECK='TRUE';
      ALLOW_CONNECT='TRUE';
    'GND_B22':
      PIN_NUMBER='(B22)';
      PINUSE='POWER';
      NO_LOAD_CHECK='Both';
      NO_IO_CHECK='Both';
      NO_ASSERT_CHECK='TRUE';
      NO_DIR_CHECK='TRUE';
      ALLOW_CONNECT='TRUE';
    'GND_B25':
      PIN_NUMBER='(B25)';
      PINUSE='POWER';
      NO_LOAD_CHECK='Both';
      NO_IO_CHECK='Both';
      NO_ASSERT_CHECK='TRUE';
      NO_DIR_CHECK='TRUE';
      ALLOW_CONNECT='TRUE';
    'GND_B28':
      PIN_NUMBER='(B28)';
      PINUSE='POWER';
      NO_LOAD_CHECK='Both';
      NO_IO_CHECK='Both';
      NO_ASSERT_CHECK='TRUE';
      NO_DIR_CHECK='TRUE';
      ALLOW_CONNECT='TRUE';
    'REFCLK_N0':
      PIN_NUMBER='(B14)';
      BIDIRECTIONAL='TRUE';
      INPUT_LOAD='(-0.01,0.01)';
      OUTPUT_LOAD='(1.0,-1.0)';
    'REFCLK_P0':
      PIN_NUMBER='(B15)';
      BIDIRECTIONAL='TRUE';
      INPUT_LOAD='(-0.01,0.01)';
      OUTPUT_LOAD='(1.0,-1.0)';
    'PET_N0':
      PIN_NUMBER='(B17)';
      BIDIRECTIONAL='TRUE';
      INPUT_LOAD='(-0.01,0.01)';
      OUTPUT_LOAD='(1.0,-1.0)';
    'PET_P0':
      PIN_NUMBER='(B18)';
      BIDIRECTIONAL='TRUE';
      INPUT_LOAD='(-0.01,0.01)';
      OUTPUT_LOAD='(1.0,-1.0)';
    'PET_N1':
      PIN_NUMBER='(B20)';
      BIDIRECTIONAL='TRUE';
      INPUT_LOAD='(-0.01,0.01)';
      OUTPUT_LOAD='(1.0,-1.0)';
    'PET_P1':
      PIN_NUMBER='(B21)';
      BIDIRECTIONAL='TRUE';
      INPUT_LOAD='(-0.01,0.01)';
      OUTPUT_LOAD='(1.0,-1.0)';
    'PET_N2':
      PIN_NUMBER='(B23)';
      BIDIRECTIONAL='TRUE';
      INPUT_LOAD='(-0.01,0.01)';
      OUTPUT_LOAD='(1.0,-1.0)';
    'PET_P2':
      PIN_NUMBER='(B24)';
      BIDIRECTIONAL='TRUE';
      INPUT_LOAD='(-0.01,0.01)';
      OUTPUT_LOAD='(1.0,-1.0)';
    'PET_N3':
      PIN_NUMBER='(B26)';
      BIDIRECTIONAL='TRUE';
      INPUT_LOAD='(-0.01,0.01)';
      OUTPUT_LOAD='(1.0,-1.0)';
    'PET_P3':
      PIN_NUMBER='(B27)';
      BIDIRECTIONAL='TRUE';
      INPUT_LOAD='(-0.01,0.01)';
      OUTPUT_LOAD='(1.0,-1.0)';
    'SMBCLK':
      PIN_NUMBER='(A7)';
      BIDIRECTIONAL='TRUE';
      INPUT_LOAD='(-0.01,0.01)';
      OUTPUT_LOAD='(1.0,-1.0)';
    'SMBDAT':
      PIN_NUMBER='(A8)';
      BIDIRECTIONAL='TRUE';
      INPUT_LOAD='(-0.01,0.01)';
      OUTPUT_LOAD='(1.0,-1.0)';
    'SMBRST#':
      PIN_NUMBER='(A9)';
      BIDIRECTIONAL='TRUE';
      INPUT_LOAD='(-0.01,0.01)';
      OUTPUT_LOAD='(1.0,-1.0)';
    'LED#_ACTIVITY':
      PIN_NUMBER='(A10)';
      BIDIRECTIONAL='TRUE';
      INPUT_LOAD='(-0.01,0.01)';
      OUTPUT_LOAD='(1.0,-1.0)';
    'PERST0#':
      PIN_NUMBER='(B10)';
      BIDIRECTIONAL='TRUE';
      INPUT_LOAD='(-0.01,0.01)';
      OUTPUT_LOAD='(1.0,-1.0)';
    'PERST1#_CLKREQ#':
      PIN_NUMBER='(A11)';
      BIDIRECTIONAL='TRUE';
      INPUT_LOAD='(-0.01,0.01)';
      OUTPUT_LOAD='(1.0,-1.0)';
    'PRSNT0#':
      PIN_NUMBER='(A12)';
      BIDIRECTIONAL='TRUE';
      INPUT_LOAD='(-0.01,0.01)';
      OUTPUT_LOAD='(1.0,-1.0)';
    'GND_A13':
      PIN_NUMBER='(A13)';
      PINUSE='POWER';
      NO_LOAD_CHECK='Both';
      NO_IO_CHECK='Both';
      NO_ASSERT_CHECK='TRUE';
      NO_DIR_CHECK='TRUE';
      ALLOW_CONNECT='TRUE';
    'GND_A16':
      PIN_NUMBER='(A16)';
      PINUSE='POWER';
      NO_LOAD_CHECK='Both';
      NO_IO_CHECK='Both';
      NO_ASSERT_CHECK='TRUE';
      NO_DIR_CHECK='TRUE';
      ALLOW_CONNECT='TRUE';
    'GND_A19':
      PIN_NUMBER='(A19)';
      PINUSE='POWER';
      NO_LOAD_CHECK='Both';
      NO_IO_CHECK='Both';
      NO_ASSERT_CHECK='TRUE';
      NO_DIR_CHECK='TRUE';
      ALLOW_CONNECT='TRUE';
    'GND_A22':
      PIN_NUMBER='(A22)';
      PINUSE='POWER';
      NO_LOAD_CHECK='Both';
      NO_IO_CHECK='Both';
      NO_ASSERT_CHECK='TRUE';
      NO_DIR_CHECK='TRUE';
      ALLOW_CONNECT='TRUE';
    'GND_A25':
      PIN_NUMBER='(A25)';
      PINUSE='POWER';
      NO_LOAD_CHECK='Both';
      NO_IO_CHECK='Both';
      NO_ASSERT_CHECK='TRUE';
      NO_DIR_CHECK='TRUE';
      ALLOW_CONNECT='TRUE';
    'GND_A28':
      PIN_NUMBER='(A28)';
      PINUSE='POWER';
      NO_LOAD_CHECK='Both';
      NO_IO_CHECK='Both';
      NO_ASSERT_CHECK='TRUE';
      NO_DIR_CHECK='TRUE';
      ALLOW_CONNECT='TRUE';
    'REFCLK_N1':
      PIN_NUMBER='(A14)';
      BIDIRECTIONAL='TRUE';
      INPUT_LOAD='(-0.01,0.01)';
      OUTPUT_LOAD='(1.0,-1.0)';
    'REFCLK_P1':
      PIN_NUMBER='(A15)';
      BIDIRECTIONAL='TRUE';
      INPUT_LOAD='(-0.01,0.01)';
      OUTPUT_LOAD='(1.0,-1.0)';
    'PER_N0':
      PIN_NUMBER='(A17)';
      BIDIRECTIONAL='TRUE';
      INPUT_LOAD='(-0.01,0.01)';
      OUTPUT_LOAD='(1.0,-1.0)';
    'PER_P0':
      PIN_NUMBER='(A18)';
      BIDIRECTIONAL='TRUE';
      INPUT_LOAD='(-0.01,0.01)';
      OUTPUT_LOAD='(1.0,-1.0)';
    'PER_N1':
      PIN_NUMBER='(A20)';
      BIDIRECTIONAL='TRUE';
      INPUT_LOAD='(-0.01,0.01)';
      OUTPUT_LOAD='(1.0,-1.0)';
    'PER_P1':
      PIN_NUMBER='(A21)';
      BIDIRECTIONAL='TRUE';
      INPUT_LOAD='(-0.01,0.01)';
      OUTPUT_LOAD='(1.0,-1.0)';
    'PER_N2':
      PIN_NUMBER='(A23)';
      BIDIRECTIONAL='TRUE';
      INPUT_LOAD='(-0.01,0.01)';
      OUTPUT_LOAD='(1.0,-1.0)';
    'PER_P2':
      PIN_NUMBER='(A24)';
      BIDIRECTIONAL='TRUE';
      INPUT_LOAD='(-0.01,0.01)';
      OUTPUT_LOAD='(1.0,-1.0)';
    'PER_N3':
      PIN_NUMBER='(A26)';
      BIDIRECTIONAL='TRUE';
      INPUT_LOAD='(-0.01,0.01)';
      OUTPUT_LOAD='(1.0,-1.0)';
    'PER_P3':
      PIN_NUMBER='(A27)';
      BIDIRECTIONAL='TRUE';
      INPUT_LOAD='(-0.01,0.01)';
      OUTPUT_LOAD='(1.0,-1.0)';
    'G2':
      PIN_NUMBER='(G2)';
      PINUSE='POWER';
      NO_LOAD_CHECK='Both';
      NO_IO_CHECK='Both';
      NO_ASSERT_CHECK='TRUE';
      NO_DIR_CHECK='TRUE';
      ALLOW_CONNECT='TRUE';
    'G1':
      PIN_NUMBER='(G1)';
      PINUSE='POWER';
      NO_LOAD_CHECK='Both';
      NO_IO_CHECK='Both';
      NO_ASSERT_CHECK='TRUE';
      NO_DIR_CHECK='TRUE';
      ALLOW_CONNECT='TRUE';
  end_pin;
  body
    PART_NAME='SCONN56_123276793';
    BODY_NAME='SCONN56_123276793';
    PHYS_DES_PREFIX='J';
    CLASS='IO';
    NC_PINS='(H1,H2)';
  end_body;
end_primitive;

END.
